FILE_TYPE = CONNECTIVITY;
{Allegro Design Entry HDL 17.2-2016 S081 (4005846) 1/11/2022}
"PAGE_NUMBER" = 37;
0"NC";
1"VCCIO3\g";
%"LCMXO3LF2100C5BG256C"
"4","(-4825,4625)","0","pure_quanta","I1";
;
PART_NUMBER"AJ021000T03"
VALUE"LCMXO3LF-2100C-5BG256C"
MATERIAL"IC"
PART_TYPE"SMLF"
CDS_LMAN_SYM_OUTLINE"-500,600,500,-600"
NEEDS_NO_SIZE"TRUE"
CDS_LIB"pure_quanta"
LOCATION"U25"
$SEC"4"
CDS_SEC"4";
"PL13B"
$PN"N1"0;
"PL13A"
$PN"M3"0;
"PL13D"
$PN"P1"0;
"PL13C"
$PN"N2"0;
"VCCIO3"
$PN"M4"1;
"PL14D"
$PN"P2"0;
"PL14C"
$PN"R1"0;
"PL14B"
$PN"N3"0;
"PL14A"
$PN"M2"0;
"PL12B||PCLKC3_0"
$PN"M1"0;
"PL12A||PCLKT3_0"
$PN"L2"0;
"PL12D"
$PN"L4"0;
"PL12C"
$PN"K5"0;
"PL11D"
$PN"L5"0;
"PL11C"
$PN"K4"0;
"PL11B"
$PN"L3"0;
"PL11A"
$PN"L1"0;
%"UNIVERSAL_POWER"
"1","(-3800,4325)","0","logical_power","I3";
;
HDL_POWER"VCCIO3"
CDS_LIB"logical_power";
"A"1;
END.
